(kicad_pcb
	(version 20260206)
	(generator "pcbnew")
	(generator_version "10.0")
	(general
		(thickness 1.6)
		(legacy_teardrops no)
	)
	(paper "A4")
	(title_block
		(title "baseboard — 13948-1b.1110WZS1818.brd")
		(comment 1 "Honey Badger (Wiwynn) / footprint 852 of 2523 (SU2), pads 123-241 of 896")
	)
	(layers
		(0 "F.Cu" signal "TOP")
		(4 "In1.Cu" signal "L2GND")
		(6 "In2.Cu" signal "L3")
		(8 "In3.Cu" signal "L4VCC")
		(10 "In4.Cu" signal "L5VCC")
		(12 "In5.Cu" signal "L6")
		(14 "In6.Cu" signal "L7GND")
		(2 "B.Cu" signal "BOTTOM")
		(9 "F.Adhes" user "F.Adhesive")
		(11 "B.Adhes" user "B.Adhesive")
		(13 "F.Paste" user "Package Geometry/Pastemask Top")
		(15 "B.Paste" user "Package Geometry/Pastemask Bottom")
		(5 "F.SilkS" user "Ref Des/Silkscreen Top")
		(7 "B.SilkS" user "Ref Des/Silkscreen Bottom")
		(1 "F.Mask" user "Board Geometry/Soldermask Top")
		(3 "B.Mask" user "Board Geometry/Soldermask Bottom")
		(17 "Dwgs.User" user "User.Drawings")
		(19 "Cmts.User" user "User.Comments")
		(21 "Eco1.User" user "User.Eco1")
		(23 "Eco2.User" user "User.Eco2")
		(25 "Edge.Cuts" user "Board Geometry/Outline")
		(27 "Margin" user)
		(31 "F.CrtYd" user "Package Geometry/Place Bound Top")
		(29 "B.CrtYd" user "Package Geometry/Place Bound Bottom")
		(35 "F.Fab" user "Ref Des/Assembly Top")
		(33 "B.Fab" user "Ref Des/Assembly Bottom")
	)
	(footprint ""
		(layer "F.Cu")
		(at 102.350062 -44.99991)
		(property "Reference" "SU2"
			(at 0 0 0)
			(layer "F.SilkS")
			(hide yes)
			(effects
				(font
					(size 1.27 1.27)
				)
			)
		)
		(property "Value" "SAS3008C0-1-DB-500020657-1-GP"
			(at -20.374102 -5.0292 0)
			(unlocked yes)
			(layer "F.Fab")
			(hide yes)
			(effects
				(font
					(size 1.016 1.016)
					(thickness 0.1524)
				)
			)
		)
		(property "Device Type" "BGA896D25H78"
			(at -20.374102 -6.5532 0)
			(unlocked yes)
			(layer "F.Fab")
			(hide yes)
			(effects
				(font
					(size 1.016 1.016)
					(thickness 0.1524)
				)
			)
		)
		(duplicate_pad_numbers_are_jumpers no)
		(pad "AD5" smd circle
			(at -8.400034 6.800088)
			(size 0.3556 0.3556)
			(layers "F.Cu" "F.Mask" "F.Paste")
			(net "3008_SAS_RX_N3")
		)
		(pad "AD6" smd circle
			(at -7.599934 6.800088)
			(size 0.3556 0.3556)
			(layers "F.Cu" "F.Mask" "F.Paste")
			(net "GND")
		)
		(pad "AD7" smd circle
			(at -6.800088 6.800088)
			(size 0.3556 0.3556)
			(layers "F.Cu" "F.Mask" "F.Paste")
			(net "SAS0_AVDD")
		)
		(pad "AD8" smd circle
			(at -5.999988 6.800088)
			(size 0.3556 0.3556)
			(layers "F.Cu" "F.Mask" "F.Paste")
			(net "GND")
		)
		(pad "AD9" smd circle
			(at -5.199888 6.800088)
			(size 0.3556 0.3556)
			(layers "F.Cu" "F.Mask" "F.Paste")
			(net "PCE_AVDD")
		)
		(pad "AD10" smd circle
			(at -4.400042 6.800088)
			(size 0.3556 0.3556)
			(layers "F.Cu" "F.Mask" "F.Paste")
			(net "GND")
		)
		(pad "AD11" smd circle
			(at -3.599942 6.800088)
			(size 0.3556 0.3556)
			(layers "F.Cu" "F.Mask" "F.Paste")
			(net "PCE_AVDD")
		)
		(pad "AD12" smd circle
			(at -2.800096 6.800088)
			(size 0.3556 0.3556)
			(layers "F.Cu" "F.Mask" "F.Paste")
			(net "GND")
		)
		(pad "AD13" smd circle
			(at -1.999996 6.800088)
			(size 0.3556 0.3556)
			(layers "F.Cu" "F.Mask" "F.Paste")
			(net "PCE_AVDD")
		)
		(pad "AD14" smd circle
			(at -1.199896 6.800088)
			(size 0.3556 0.3556)
			(layers "F.Cu" "F.Mask" "F.Paste")
			(net "GND")
		)
		(pad "AD15" smd circle
			(at -0.40005 6.800088)
			(size 0.3556 0.3556)
			(layers "F.Cu" "F.Mask" "F.Paste")
			(net "PCE_AVDD")
		)
		(pad "AD16" smd circle
			(at 0.40005 6.800088)
			(size 0.3556 0.3556)
			(layers "F.Cu" "F.Mask" "F.Paste")
			(net "GND")
		)
		(pad "AD17" smd circle
			(at 1.199896 6.800088)
			(size 0.3556 0.3556)
			(layers "F.Cu" "F.Mask" "F.Paste")
			(net "GND")
		)
		(pad "AD18" smd circle
			(at 1.999996 6.800088)
			(size 0.3556 0.3556)
			(layers "F.Cu" "F.Mask" "F.Paste")
			(net "GND")
		)
		(pad "AD19" smd circle
			(at 2.800096 6.800088)
			(size 0.3556 0.3556)
			(layers "F.Cu" "F.Mask" "F.Paste")
			(net "GND")
		)
		(pad "AD20" smd circle
			(at 3.599942 6.800088)
			(size 0.3556 0.3556)
			(layers "F.Cu" "F.Mask" "F.Paste")
			(net "GND")
		)
		(pad "AD21" smd circle
			(at 4.400042 6.800088)
			(size 0.3556 0.3556)
			(layers "F.Cu" "F.Mask" "F.Paste")
			(net "GND")
		)
		(pad "AD22" smd circle
			(at 5.199888 6.800088)
			(size 0.3556 0.3556)
			(layers "F.Cu" "F.Mask" "F.Paste")
			(net "GND")
		)
		(pad "AD23" smd circle
			(at 5.999988 6.800088)
			(size 0.3556 0.3556)
			(layers "F.Cu" "F.Mask" "F.Paste")
			(net "GND")
		)
		(pad "AD24" smd circle
			(at 6.800088 6.800088)
			(size 0.3556 0.3556)
			(layers "F.Cu" "F.Mask" "F.Paste")
			(net "GND")
		)
		(pad "AD25" smd circle
			(at 7.599934 6.800088)
			(size 0.3556 0.3556)
			(layers "F.Cu" "F.Mask" "F.Paste")
			(net "GND")
		)
		(pad "AD26" smd circle
			(at 8.400034 6.800088)
			(size 0.3556 0.3556)
			(layers "F.Cu" "F.Mask" "F.Paste")
			(net "P1V8_C")
		)
		(pad "AD27" smd circle
			(at 9.19988 6.800088)
			(size 0.3556 0.3556)
			(layers "F.Cu" "F.Mask" "F.Paste")
			(net "GND")
		)
		(pad "AD28" smd circle
			(at 9.99998 6.800088)
			(size 0.3556 0.3556)
			(layers "F.Cu" "F.Mask" "F.Paste")
			(net "IOC_GPIO_29")
		)
		(pad "AD29" smd circle
			(at 10.80008 6.800088)
			(size 0.3556 0.3556)
			(layers "F.Cu" "F.Mask" "F.Paste")
			(net "IOC_GPIO_27")
		)
		(pad "AD30" smd circle
			(at 11.599926 6.800088)
			(size 0.3556 0.3556)
			(layers "F.Cu" "F.Mask" "F.Paste")
			(net "IOC_GPIO_17")
		)
		(pad "AE1" smd circle
			(at -11.599926 7.599934)
			(size 0.3556 0.3556)
			(layers "F.Cu" "F.Mask" "F.Paste")
			(net "SAS3008_RAID_TX_C_P2")
		)
		(pad "AE2" smd circle
			(at -10.80008 7.599934)
			(size 0.3556 0.3556)
			(layers "F.Cu" "F.Mask" "F.Paste")
			(net "SAS3008_RAID_TX_C_N2")
		)
		(pad "AE3" smd circle
			(at -9.99998 7.599934)
			(size 0.3556 0.3556)
			(layers "F.Cu" "F.Mask" "F.Paste")
			(net "GND")
		)
		(pad "AE4" smd circle
			(at -9.19988 7.599934)
			(size 0.3556 0.3556)
			(layers "F.Cu" "F.Mask" "F.Paste")
			(net "3008_SAS_RX_P2")
		)
		(pad "AE5" smd circle
			(at -8.400034 7.599934)
			(size 0.3556 0.3556)
			(layers "F.Cu" "F.Mask" "F.Paste")
			(net "3008_SAS_RX_N2")
		)
		(pad "AE6" smd circle
			(at -7.599934 7.599934)
			(size 0.3556 0.3556)
			(layers "F.Cu" "F.Mask" "F.Paste")
			(net "GND")
		)
		(pad "AE7" smd circle
			(at -6.800088 7.599934)
			(size 0.3556 0.3556)
			(layers "F.Cu" "F.Mask" "F.Paste")
			(net "GND")
		)
		(pad "AE8" smd circle
			(at -5.999988 7.599934)
			(size 0.3556 0.3556)
			(layers "F.Cu" "F.Mask" "F.Paste")
			(net "P1V5_C")
		)
		(pad "AE9" smd circle
			(at -5.199888 7.599934)
			(size 0.3556 0.3556)
			(layers "F.Cu" "F.Mask" "F.Paste")
			(net "GND")
		)
		(pad "AE10" smd circle
			(at -4.400042 7.599934)
			(size 0.3556 0.3556)
			(layers "F.Cu" "F.Mask" "F.Paste")
			(net "P1V5_C")
		)
		(pad "AE11" smd circle
			(at -3.599942 7.599934)
			(size 0.3556 0.3556)
			(layers "F.Cu" "F.Mask" "F.Paste")
			(net "GND")
		)
		(pad "AE12" smd circle
			(at -2.800096 7.599934)
			(size 0.3556 0.3556)
			(layers "F.Cu" "F.Mask" "F.Paste")
			(net "P1V5_C")
		)
		(pad "AE13" smd circle
			(at -1.999996 7.599934)
			(size 0.3556 0.3556)
			(layers "F.Cu" "F.Mask" "F.Paste")
			(net "GND")
		)
		(pad "AE14" smd circle
			(at -1.199896 7.599934)
			(size 0.3556 0.3556)
			(layers "F.Cu" "F.Mask" "F.Paste")
			(net "P1V5_C")
		)
		(pad "AE15" smd circle
			(at -0.40005 7.599934)
			(size 0.3556 0.3556)
			(layers "F.Cu" "F.Mask" "F.Paste")
			(net "GND")
		)
		(pad "AE16" smd circle
			(at 0.40005 7.599934)
			(size 0.3556 0.3556)
			(layers "F.Cu" "F.Mask" "F.Paste")
			(net "P1V5_C")
		)
		(pad "AE17" smd circle
			(at 1.199896 7.599934)
			(size 0.3556 0.3556)
			(layers "F.Cu" "F.Mask" "F.Paste")
			(net "GND")
		)
		(pad "AE18" smd circle
			(at 1.999996 7.599934)
			(size 0.3556 0.3556)
			(layers "F.Cu" "F.Mask" "F.Paste")
			(net "GND")
		)
		(pad "AE19" smd circle
			(at 2.800096 7.599934)
			(size 0.3556 0.3556)
			(layers "F.Cu" "F.Mask" "F.Paste")
			(net "SPARE5")
		)
		(pad "AE20" smd circle
			(at 3.599942 7.599934)
			(size 0.3556 0.3556)
			(layers "F.Cu" "F.Mask" "F.Paste")
			(net "SPARE3")
		)
		(pad "AE21" smd circle
			(at 4.400042 7.599934)
			(size 0.3556 0.3556)
			(layers "F.Cu" "F.Mask" "F.Paste")
			(net "IOC_GPIO_7")
		)
		(pad "AE22" smd circle
			(at 5.199888 7.599934)
			(size 0.3556 0.3556)
			(layers "F.Cu" "F.Mask" "F.Paste")
			(net "SYS_DBMODE0")
		)
		(pad "AE23" smd circle
			(at 5.999988 7.599934)
			(size 0.3556 0.3556)
			(layers "F.Cu" "F.Mask" "F.Paste")
			(net "SYS_RST_N_1")
		)
		(pad "AE24" smd circle
			(at 6.800088 7.599934)
			(size 0.3556 0.3556)
			(layers "F.Cu" "F.Mask" "F.Paste")
			(net "GND")
		)
		(pad "AE25" smd circle
			(at 7.599934 7.599934)
			(size 0.3556 0.3556)
			(layers "F.Cu" "F.Mask" "F.Paste")
			(net "GND")
		)
		(pad "AE26" smd circle
			(at 8.400034 7.599934)
			(size 0.3556 0.3556)
			(layers "F.Cu" "F.Mask" "F.Paste")
			(net "GND")
		)
		(pad "AE27" smd circle
			(at 9.19988 7.599934)
			(size 0.3556 0.3556)
			(layers "F.Cu" "F.Mask" "F.Paste")
			(net "P1V8_C")
		)
		(pad "AE28" smd circle
			(at 9.99998 7.599934)
			(size 0.3556 0.3556)
			(layers "F.Cu" "F.Mask" "F.Paste")
			(net "UART_SERCLK")
		)
		(pad "AE29" smd circle
			(at 10.80008 7.599934)
			(size 0.3556 0.3556)
			(layers "F.Cu" "F.Mask" "F.Paste")
			(net "IOC_GPIO_39")
		)
		(pad "AE30" smd circle
			(at 11.599926 7.599934)
			(size 0.3556 0.3556)
			(layers "F.Cu" "F.Mask" "F.Paste")
			(net "IOC_GPIO_31")
		)
		(pad "AF1" smd circle
			(at -11.599926 8.400034)
			(size 0.3556 0.3556)
			(layers "F.Cu" "F.Mask" "F.Paste")
			(net "SAS0_VDDH")
		)
		(pad "AF2" smd circle
			(at -10.80008 8.400034)
			(size 0.3556 0.3556)
			(layers "F.Cu" "F.Mask" "F.Paste")
			(net "GND")
		)
		(pad "AF3" smd circle
			(at -9.99998 8.400034)
			(size 0.3556 0.3556)
			(layers "F.Cu" "F.Mask" "F.Paste")
			(net "GND")
		)
		(pad "AF4" smd circle
			(at -9.19988 8.400034)
			(size 0.3556 0.3556)
			(layers "F.Cu" "F.Mask" "F.Paste")
			(net "SAS0_AVDD")
		)
		(pad "AF5" smd circle
			(at -8.400034 8.400034)
			(size 0.3556 0.3556)
			(layers "F.Cu" "F.Mask" "F.Paste")
			(net "GND")
		)
		(pad "AF6" smd circle
			(at -7.599934 8.400034)
			(size 0.3556 0.3556)
			(layers "F.Cu" "F.Mask" "F.Paste")
			(net "GND")
		)
		(pad "AF7" smd circle
			(at -6.800088 8.400034)
			(size 0.3556 0.3556)
			(layers "F.Cu" "F.Mask" "F.Paste")
			(net "PCIE_SAS_C_CPU_RX_N0")
		)
		(pad "AF8" smd circle
			(at -5.999988 8.400034)
			(size 0.3556 0.3556)
			(layers "F.Cu" "F.Mask" "F.Paste")
			(net "PCIE_SAS_C_CPU_RX_N1")
		)
		(pad "AF9" smd circle
			(at -5.199888 8.400034)
			(size 0.3556 0.3556)
			(layers "F.Cu" "F.Mask" "F.Paste")
			(net "GND")
		)
		(pad "AF10" smd circle
			(at -4.400042 8.400034)
			(size 0.3556 0.3556)
			(layers "F.Cu" "F.Mask" "F.Paste")
			(net "PCIE_SAS_C_CPU_RX_N2")
		)
		(pad "AF11" smd circle
			(at -3.599942 8.400034)
			(size 0.3556 0.3556)
			(layers "F.Cu" "F.Mask" "F.Paste")
			(net "PCIE_SAS_C_CPU_RX_N3")
		)
		(pad "AF12" smd circle
			(at -2.800096 8.400034)
			(size 0.3556 0.3556)
			(layers "F.Cu" "F.Mask" "F.Paste")
			(net "GND")
		)
		(pad "AF13" smd circle
			(at -1.999996 8.400034)
			(size 0.3556 0.3556)
			(layers "F.Cu" "F.Mask" "F.Paste")
			(net "PCIE_SAS_C_CPU_RX_N4")
		)
		(pad "AF14" smd circle
			(at -1.199896 8.400034)
			(size 0.3556 0.3556)
			(layers "F.Cu" "F.Mask" "F.Paste")
			(net "PCIE_SAS_C_CPU_RX_N5")
		)
		(pad "AF15" smd circle
			(at -0.40005 8.400034)
			(size 0.3556 0.3556)
			(layers "F.Cu" "F.Mask" "F.Paste")
			(net "GND")
		)
		(pad "AF16" smd circle
			(at 0.40005 8.400034)
			(size 0.3556 0.3556)
			(layers "F.Cu" "F.Mask" "F.Paste")
			(net "PCIE_SAS_C_CPU_RX_N6")
		)
		(pad "AF17" smd circle
			(at 1.199896 8.400034)
			(size 0.3556 0.3556)
			(layers "F.Cu" "F.Mask" "F.Paste")
			(net "PCIE_SAS_C_CPU_RX_N7")
		)
		(pad "AF18" smd circle
			(at 1.999996 8.400034)
			(size 0.3556 0.3556)
			(layers "F.Cu" "F.Mask" "F.Paste")
			(net "GND")
		)
		(pad "AF19" smd circle
			(at 2.800096 8.400034)
			(size 0.3556 0.3556)
			(layers "F.Cu" "F.Mask" "F.Paste")
			(net "GND")
		)
		(pad "AF20" smd circle
			(at 3.599942 8.400034)
			(size 0.3556 0.3556)
			(layers "F.Cu" "F.Mask" "F.Paste")
			(net "P1V8_C")
		)
		(pad "AF21" smd circle
			(at 4.400042 8.400034)
			(size 0.3556 0.3556)
			(layers "F.Cu" "F.Mask" "F.Paste")
			(net "GND")
		)
		(pad "AF22" smd circle
			(at 5.199888 8.400034)
			(size 0.3556 0.3556)
			(layers "F.Cu" "F.Mask" "F.Paste")
			(net "P1V8_C")
		)
		(pad "AF23" smd circle
			(at 5.999988 8.400034)
			(size 0.3556 0.3556)
			(layers "F.Cu" "F.Mask" "F.Paste")
			(net "GND")
		)
		(pad "AF24" smd circle
			(at 6.800088 8.400034)
			(size 0.3556 0.3556)
			(layers "F.Cu" "F.Mask" "F.Paste")
			(net "P1V8_C")
		)
		(pad "AF25" smd circle
			(at 7.599934 8.400034)
			(size 0.3556 0.3556)
			(layers "F.Cu" "F.Mask" "F.Paste")
			(net "GND")
		)
		(pad "AF26" smd circle
			(at 8.400034 8.400034)
			(size 0.3556 0.3556)
			(layers "F.Cu" "F.Mask" "F.Paste")
			(net "P1V8_C")
		)
		(pad "AF27" smd circle
			(at 9.19988 8.400034)
			(size 0.3556 0.3556)
			(layers "F.Cu" "F.Mask" "F.Paste")
			(net "GND")
		)
		(pad "AF28" smd circle
			(at 9.99998 8.400034)
			(size 0.3556 0.3556)
			(layers "F.Cu" "F.Mask" "F.Paste")
			(net "IOC_GPIO_26")
		)
		(pad "AF29" smd circle
			(at 10.80008 8.400034)
			(size 0.3556 0.3556)
			(layers "F.Cu" "F.Mask" "F.Paste")
			(net "IOC_GPIO_0")
		)
		(pad "AF30" smd circle
			(at 11.599926 8.400034)
			(size 0.3556 0.3556)
			(layers "F.Cu" "F.Mask" "F.Paste")
			(net "IOC_GPIO_16")
		)
		(pad "AG1" smd circle
			(at -11.599926 9.19988)
			(size 0.3556 0.3556)
			(layers "F.Cu" "F.Mask" "F.Paste")
			(net "SAS3008_RAID_TX_C_P1")
		)
		(pad "AG2" smd circle
			(at -10.80008 9.19988)
			(size 0.3556 0.3556)
			(layers "F.Cu" "F.Mask" "F.Paste")
			(net "SAS3008_RAID_TX_C_N1")
		)
		(pad "AG3" smd circle
			(at -9.99998 9.19988)
			(size 0.3556 0.3556)
			(layers "F.Cu" "F.Mask" "F.Paste")
			(net "GND")
		)
		(pad "AG4" smd circle
			(at -9.19988 9.19988)
			(size 0.3556 0.3556)
			(layers "F.Cu" "F.Mask" "F.Paste")
			(net "3008_SAS_RX_P1")
		)
		(pad "AG5" smd circle
			(at -8.400034 9.19988)
			(size 0.3556 0.3556)
			(layers "F.Cu" "F.Mask" "F.Paste")
			(net "3008_SAS_RX_N1")
		)
		(pad "AG6" smd circle
			(at -7.599934 9.19988)
			(size 0.3556 0.3556)
			(layers "F.Cu" "F.Mask" "F.Paste")
			(net "GND")
		)
		(pad "AG7" smd circle
			(at -6.800088 9.19988)
			(size 0.3556 0.3556)
			(layers "F.Cu" "F.Mask" "F.Paste")
			(net "PCIE_SAS_C_CPU_RX_P0")
		)
		(pad "AG8" smd circle
			(at -5.999988 9.19988)
			(size 0.3556 0.3556)
			(layers "F.Cu" "F.Mask" "F.Paste")
			(net "PCIE_SAS_C_CPU_RX_P1")
		)
		(pad "AG9" smd circle
			(at -5.199888 9.19988)
			(size 0.3556 0.3556)
			(layers "F.Cu" "F.Mask" "F.Paste")
			(net "P1V5_C")
		)
		(pad "AG10" smd circle
			(at -4.400042 9.19988)
			(size 0.3556 0.3556)
			(layers "F.Cu" "F.Mask" "F.Paste")
			(net "PCIE_SAS_C_CPU_RX_P2")
		)
		(pad "AG11" smd circle
			(at -3.599942 9.19988)
			(size 0.3556 0.3556)
			(layers "F.Cu" "F.Mask" "F.Paste")
			(net "PCIE_SAS_C_CPU_RX_P3")
		)
		(pad "AG12" smd circle
			(at -2.800096 9.19988)
			(size 0.3556 0.3556)
			(layers "F.Cu" "F.Mask" "F.Paste")
			(net "P1V5_C")
		)
		(pad "AG13" smd circle
			(at -1.999996 9.19988)
			(size 0.3556 0.3556)
			(layers "F.Cu" "F.Mask" "F.Paste")
			(net "PCIE_SAS_C_CPU_RX_P4")
		)
		(pad "AG14" smd circle
			(at -1.199896 9.19988)
			(size 0.3556 0.3556)
			(layers "F.Cu" "F.Mask" "F.Paste")
			(net "PCIE_SAS_C_CPU_RX_P5")
		)
		(pad "AG15" smd circle
			(at -0.40005 9.19988)
			(size 0.3556 0.3556)
			(layers "F.Cu" "F.Mask" "F.Paste")
			(net "GND")
		)
		(pad "AG16" smd circle
			(at 0.40005 9.19988)
			(size 0.3556 0.3556)
			(layers "F.Cu" "F.Mask" "F.Paste")
			(net "PCIE_SAS_C_CPU_RX_P6")
		)
		(pad "AG17" smd circle
			(at 1.199896 9.19988)
			(size 0.3556 0.3556)
			(layers "F.Cu" "F.Mask" "F.Paste")
			(net "PCIE_SAS_C_CPU_RX_P7")
		)
		(pad "AG18" smd circle
			(at 1.999996 9.19988)
			(size 0.3556 0.3556)
			(layers "F.Cu" "F.Mask" "F.Paste")
			(net "P1V5_C")
		)
		(pad "AG19" smd circle
			(at 2.800096 9.19988)
			(size 0.3556 0.3556)
			(layers "F.Cu" "F.Mask" "F.Paste")
			(net "P1V8_C")
		)
		(pad "AG20" smd circle
			(at 3.599942 9.19988)
			(size 0.3556 0.3556)
			(layers "F.Cu" "F.Mask" "F.Paste")
			(net "GND")
		)
		(pad "AG21" smd circle
			(at 4.400042 9.19988)
			(size 0.3556 0.3556)
			(layers "F.Cu" "F.Mask" "F.Paste")
			(net "P1V8_C")
		)
		(pad "AG22" smd circle
			(at 5.199888 9.19988)
			(size 0.3556 0.3556)
			(layers "F.Cu" "F.Mask" "F.Paste")
			(net "GND")
		)
		(pad "AG23" smd circle
			(at 5.999988 9.19988)
			(size 0.3556 0.3556)
			(layers "F.Cu" "F.Mask" "F.Paste")
			(net "P1V8_C")
		)
		(pad "AG24" smd circle
			(at 6.800088 9.19988)
			(size 0.3556 0.3556)
			(layers "F.Cu" "F.Mask" "F.Paste")
			(net "GND")
		)
		(pad "AG25" smd circle
			(at 7.599934 9.19988)
			(size 0.3556 0.3556)
			(layers "F.Cu" "F.Mask" "F.Paste")
			(net "P1V8_C")
		)
		(pad "AG26" smd circle
			(at 8.400034 9.19988)
			(size 0.3556 0.3556)
			(layers "F.Cu" "F.Mask" "F.Paste")
			(net "GND")
		)
		(pad "AG27" smd circle
			(at 9.19988 9.19988)
			(size 0.3556 0.3556)
			(layers "F.Cu" "F.Mask" "F.Paste")
			(net "P1V8_C")
		)
		(pad "AG28" smd circle
			(at 9.99998 9.19988)
			(size 0.3556 0.3556)
			(layers "F.Cu" "F.Mask" "F.Paste")
			(net "IOC_GPIO_25")
		)
		(pad "AG29" smd circle
			(at 10.80008 9.19988)
			(size 0.3556 0.3556)
			(layers "F.Cu" "F.Mask" "F.Paste")
			(net "IOC_GPIO_18")
		)
		(pad "AG30" smd circle
			(at 11.599926 9.19988)
			(size 0.3556 0.3556)
			(layers "F.Cu" "F.Mask" "F.Paste")
			(net "IOC_GPIO_21")
		)
		(pad "AH1" smd circle
			(at -11.599926 9.99998)
			(size 0.4064 0.4064)
			(layers "F.Cu" "F.Mask" "F.Paste")
			(net "SAS3008_RAID_TX_C_P0")
		)
		(pad "AH2" smd circle
			(at -10.80008 9.99998)
			(size 0.4064 0.4064)
			(layers "F.Cu" "F.Mask" "F.Paste")
			(net "SAS3008_RAID_TX_C_N0")
		)
		(pad "AH3" smd circle
			(at -9.99998 9.99998)
			(size 0.4064 0.4064)
			(layers "F.Cu" "F.Mask" "F.Paste")
			(net "GND")
		)
	)
)
